# SCM (Grand Teton) — schematic netlist excerpt (pin names and nets, part order shuffled) for the footprints in the layout excerpt that follows; sources: Cadence DE-HDL packaged netlist, KiCad conversion of 12092022_DA0F0TMDCD0_F0T_Management_Board_D_brd_V3_OCP.brd

R398  Q_RES  0 5% CHIP  pkg 0402LF  page 15 : A = JTAG_1_BMC_TDO ; B = JTAG_1_BMC_TDO_R
C150  Q_CAP  0.001UF 50V 10% EMPTY  pkg C0402  page 51 : A = PWRGD_P5V_AUX_R ; B = GND

(kicad_pcb
	(version 20260206)
	(generator "pcbnew")
	(generator_version "10.0")
	(general
		(thickness 1.6)
		(legacy_teardrops no)
	)
	(paper "A4")
	(title_block
		(title "12092022_DA0F0TMDCD0_F0T_Management_Board_D_brd_V3_OCP.brd")
		(comment 1 "Grand Teton / footprints 1111-1112 of 1440")
	)
	(layers
		(0 "F.Cu" signal "TOP")
		(4 "In1.Cu" signal "GND")
		(6 "In2.Cu" signal "IN1")
		(8 "In3.Cu" signal "GND1")
		(10 "In4.Cu" signal "IN2")
		(12 "In5.Cu" signal "VCC")
		(14 "In6.Cu" signal "VCC1")
		(16 "In7.Cu" signal "IN3")
		(18 "In8.Cu" signal "GND2")
		(20 "In9.Cu" signal "IN4")
		(22 "In10.Cu" signal "GND3")
		(2 "B.Cu" signal "BOTTOM")
		(9 "F.Adhes" user "F.Adhesive")
		(11 "B.Adhes" user "B.Adhesive")
		(13 "F.Paste" user "Package Geometry/Pastemask Top")
		(15 "B.Paste" user "Package Geometry/Pastemask Bottom")
		(5 "F.SilkS" user "Ref Des/Silkscreen Top")
		(7 "B.SilkS" user "Ref Des/Silkscreen Bottom")
		(1 "F.Mask" user "Board Geometry/Soldermask Top")
		(3 "B.Mask" user "Board Geometry/Soldermask Bottom")
		(17 "Dwgs.User" user "User.Drawings")
		(19 "Cmts.User" user "User.Comments")
		(21 "Eco1.User" user "User.Eco1")
		(23 "Eco2.User" user "User.Eco2")
		(25 "Edge.Cuts" user "Board Geometry/Outline")
		(27 "Margin" user)
		(31 "F.CrtYd" user "Package Geometry/Place Bound Top")
		(29 "B.CrtYd" user "Package Geometry/Place Bound Bottom")
		(35 "F.Fab" user "Ref Des/Assembly Top")
		(33 "B.Fab" user "Ref Des/Assembly Bottom")
	)
	(footprint ""
		(layer "B.Cu")
		(at 11.303 -54.356 90)
		(property "Reference" "C150"
			(at 0 0 90)
			(layer "B.SilkS")
			(hide yes)
			(effects
				(font
					(size 1.27 1.27)
				)
				(justify mirror)
			)
		)
		(property "Value" ""
			(at 0 0 90)
			(layer "B.Fab")
			(effects
				(font
					(size 1.27 1.27)
				)
				(justify mirror)
			)
		)
		(duplicate_pad_numbers_are_jumpers no)
		(fp_line
			(start 0.7874 -0.4064)
			(end -0.7874 -0.4064)
			(stroke
				(width 0.1524)
				(type default)
			)
			(layer "B.SilkS")
		)
		(fp_line
			(start -0.7874 -0.4064)
			(end -0.7874 0.4064)
			(stroke
				(width 0.1524)
				(type default)
			)
			(layer "B.SilkS")
		)
		(fp_line
			(start 0.7874 0.4064)
			(end 0.7874 -0.4064)
			(stroke
				(width 0.1524)
				(type default)
			)
			(layer "B.SilkS")
		)
		(fp_line
			(start -0.7874 0.4064)
			(end 0.7874 0.4064)
			(stroke
				(width 0.1524)
				(type default)
			)
			(layer "B.SilkS")
		)
		(fp_line
			(start 0.67945 -0.305054)
			(end 0.12065 -0.305054)
			(stroke
				(width 0.1)
				(type default)
			)
			(layer "B.Fab")
		)
		(fp_line
			(start 0.12065 -0.305054)
			(end 0.12065 -0.2794)
			(stroke
				(width 0.1)
				(type default)
			)
			(layer "B.Fab")
		)
		(fp_line
			(start -0.12065 -0.3048)
			(end -0.67945 -0.3048)
			(stroke
				(width 0.1)
				(type default)
			)
			(layer "B.Fab")
		)
		(fp_line
			(start -0.67945 -0.3048)
			(end -0.67945 0.3048)
			(stroke
				(width 0.1)
				(type default)
			)
			(layer "B.Fab")
		)
		(fp_line
			(start 0.12065 -0.2794)
			(end -0.12065 -0.2794)
			(stroke
				(width 0.1)
				(type default)
			)
			(layer "B.Fab")
		)
		(fp_line
			(start -0.12065 -0.2794)
			(end -0.12065 -0.3048)
			(stroke
				(width 0.1)
				(type default)
			)
			(layer "B.Fab")
		)
		(fp_line
			(start 0.12065 0.2794)
			(end 0.12065 0.3048)
			(stroke
				(width 0.1)
				(type default)
			)
			(layer "B.Fab")
		)
		(fp_line
			(start -0.120396 0.2794)
			(end 0.12065 0.2794)
			(stroke
				(width 0.1)
				(type default)
			)
			(layer "B.Fab")
		)
		(fp_line
			(start 0.67945 0.3048)
			(end 0.67945 -0.305054)
			(stroke
				(width 0.1)
				(type default)
			)
			(layer "B.Fab")
		)
		(fp_line
			(start 0.12065 0.3048)
			(end 0.67945 0.3048)
			(stroke
				(width 0.1)
				(type default)
			)
			(layer "B.Fab")
		)
		(fp_line
			(start -0.120396 0.3048)
			(end -0.120396 0.2794)
			(stroke
				(width 0.1)
				(type default)
			)
			(layer "B.Fab")
		)
		(fp_line
			(start -0.67945 0.3048)
			(end -0.120396 0.3048)
			(stroke
				(width 0.1)
				(type default)
			)
			(layer "B.Fab")
		)
		(pad "1" smd circle
			(at 0.40005 0 270)
			(size 0 0)
			(layers "B.Cu" "B.Mask" "B.Paste")
			(net "PWRGD_P5V_AUX_R")
		)
		(pad "2" smd circle
			(at -0.40005 0 270)
			(size 0 0)
			(layers "B.Cu" "B.Mask" "B.Paste")
			(net "GND")
		)
	)
	(footprint ""
		(layer "B.Cu")
		(at 34.4424 -49.6824)
		(property "Reference" "R398"
			(at 0 0 0)
			(layer "B.SilkS")
			(hide yes)
			(effects
				(font
					(size 1.27 1.27)
				)
				(justify mirror)
			)
		)
		(property "Value" ""
			(at 0 0 0)
			(layer "B.Fab")
			(effects
				(font
					(size 1.27 1.27)
				)
				(justify mirror)
			)
		)
		(duplicate_pad_numbers_are_jumpers no)
		(fp_line
			(start -0.7874 -0.4064)
			(end -0.7874 0.4064)
			(stroke
				(width 0.1524)
				(type default)
			)
			(layer "B.SilkS")
		)
		(fp_line
			(start -0.7874 0.4064)
			(end 0.7874 0.4064)
			(stroke
				(width 0.1524)
				(type default)
			)
			(layer "B.SilkS")
		)
		(fp_line
			(start 0.7874 -0.4064)
			(end -0.7874 -0.4064)
			(stroke
				(width 0.1524)
				(type default)
			)
			(layer "B.SilkS")
		)
		(fp_line
			(start 0.7874 0.4064)
			(end 0.7874 -0.4064)
			(stroke
				(width 0.1524)
				(type default)
			)
			(layer "B.SilkS")
		)
		(fp_line
			(start -0.67945 -0.3048)
			(end -0.67945 0.3048)
			(stroke
				(width 0.1)
				(type default)
			)
			(layer "B.Fab")
		)
		(fp_line
			(start -0.67945 0.3048)
			(end -0.120396 0.3048)
			(stroke
				(width 0.1)
				(type default)
			)
			(layer "B.Fab")
		)
		(fp_line
			(start -0.12065 -0.3048)
			(end -0.67945 -0.3048)
			(stroke
				(width 0.1)
				(type default)
			)
			(layer "B.Fab")
		)
		(fp_line
			(start -0.12065 -0.2794)
			(end -0.12065 -0.3048)
			(stroke
				(width 0.1)
				(type default)
			)
			(layer "B.Fab")
		)
		(fp_line
			(start -0.120396 0.2794)
			(end 0.12065 0.2794)
			(stroke
				(width 0.1)
				(type default)
			)
			(layer "B.Fab")
		)
		(fp_line
			(start -0.120396 0.3048)
			(end -0.120396 0.2794)
			(stroke
				(width 0.1)
				(type default)
			)
			(layer "B.Fab")
		)
		(fp_line
			(start 0.12065 -0.305054)
			(end 0.12065 -0.2794)
			(stroke
				(width 0.1)
				(type default)
			)
			(layer "B.Fab")
		)
		(fp_line
			(start 0.12065 -0.2794)
			(end -0.12065 -0.2794)
			(stroke
				(width 0.1)
				(type default)
			)
			(layer "B.Fab")
		)
		(fp_line
			(start 0.12065 0.2794)
			(end 0.12065 0.3048)
			(stroke
				(width 0.1)
				(type default)
			)
			(layer "B.Fab")
		)
		(fp_line
			(start 0.12065 0.3048)
			(end 0.67945 0.3048)
			(stroke
				(width 0.1)
				(type default)
			)
			(layer "B.Fab")
		)
		(fp_line
			(start 0.67945 -0.305054)
			(end 0.12065 -0.305054)
			(stroke
				(width 0.1)
				(type default)
			)
			(layer "B.Fab")
		)
		(fp_line
			(start 0.67945 0.3048)
			(end 0.67945 -0.305054)
			(stroke
				(width 0.1)
				(type default)
			)
			(layer "B.Fab")
		)
		(pad "1" smd circle
			(at 0.40005 0 180)
			(size 0 0)
			(layers "B.Cu" "B.Mask" "B.Paste")
			(net "JTAG_1_BMC_TDO")
		)
		(pad "2" smd circle
			(at -0.40005 0 180)
			(size 0 0)
			(layers "B.Cu" "B.Mask" "B.Paste")
			(net "JTAG_1_BMC_TDO_R")
		)
	)
)
